FILE_TYPE = MACRO_DRAWING;
SET COLOR_WIRE YELLOW;
SET COLOR_PROP ORANGE;
SET COLOR_DOT WHITE;
SET COLOR_ARC YELLOW;
SET COLOR_BODY GREEN;
SET COLOR_NOTE PURPLE;
SET PROP_DISPLAY VALUE;
SET PAGE_NUMBER P26;
SET PATH_NUMBER P71;
FORCEADD UNIVERSAL_POWER..1
(-1800 1650);
FORCEPROP 3 LASTPIN (-1800 1600) SIG_NAME P3V3_AUX\g
J 0
(-1790 1610);
DISPLAY 0.659574 (-1790 1610);
PAINT MONO (-1790 1610);
DISPLAY INVISIBLE (-1790 1610);
FORCEPROP 1 LAST HDL_POWER P3V3_AUX
J 1
(-1800 1700);
DISPLAY 0.702128 (-1800 1700);
PAINT GREEN (-1800 1700);
FORCEPROP 2 LAST CDS_LIB logical_power
J 0
(-1800 1650);
DISPLAY INVISIBLE (-1800 1650);
FORCEPROP 1 LAST PATH I10
J 0
(-1750 1675);
DISPLAY 0.872340 (-1750 1675);
PAINT AQUA (-1750 1675);
DISPLAY INVISIBLE (-1750 1675);
FORCEADD Q_RES..2
(-1450 1175);
FORCEPROP 1 LAST VALUE 4.7K
J 0
(-1405 1250);
DISPLAY 0.510638 (-1405 1250);
PAINT SKYBLUE (-1405 1250);
FORCEPROP 1 LAST TOLERANCE 1%
J 0
(-1405 1200);
DISPLAY 0.510638 (-1405 1200);
PAINT SKYBLUE (-1405 1200);
FORCEPROP 1 LAST PACK_TYPE 0402LF
J 0
(-1400 1125);
DISPLAY 0.510638 (-1400 1125);
PAINT SKYBLUE (-1400 1125);
FORCEPROP 1 LAST WATTAGE 1/16W
J 0
(-1400 1075);
DISPLAY 0.510638 (-1400 1075);
PAINT SKYBLUE (-1400 1075);
FORCEPROP 1 LAST MATERIAL EMPTY
J 0
(-1400 1150);
DISPLAY 0.510638 (-1400 1150);
PAINT RED (-1400 1150);
FORCEPROP 2 LAST CDS_LIB pure_quanta
J 0
(-1450 1175);
DISPLAY INVISIBLE (-1450 1175);
FORCEPROP 2 LAST SEC_TYPE 0402LF
J 0
(-1400 1400);
DISPLAY 0.680851 (-1400 1400);
DISPLAY INVISIBLE (-1400 1400);
FORCEPROP 1 LAST PATH I11
J 0
(-1400 1350);
DISPLAY 0.978723 (-1400 1350);
PAINT WHITE (-1400 1350);
DISPLAY INVISIBLE (-1400 1350);
FORCEPROP 1 LAST PART_NUMBER CS24702FB06
J 0
(-1410 1050);
DISPLAY 0.510638 (-1410 1050);
PAINT WHITE (-1410 1050);
DISPLAY INVISIBLE (-1410 1050);
FORCEPROP 1 LAST LOCATION R13
J 0
(-1405 1300);
DISPLAY 0.702128 (-1405 1300);
PAINT YELLOW (-1405 1300);
FORCEPROP 1 LASTPIN (-1450 1275) $PN 1
J 0
(-1445 1237);
DISPLAY 0.808511 (-1445 1237);
PAINT WHITE (-1445 1237);
FORCEPROP 1 LASTPIN (-1450 1075) $PN 2
J 0
(-1445 1085);
DISPLAY 0.808511 (-1445 1085);
PAINT WHITE (-1445 1085);
FORCEPROP 2 LAST SEC 1
J 0
(-1400 1400);
DISPLAY 0.680851 (-1400 1400);
PAINT MONO (-1400 1400);
DISPLAY INVISIBLE (-1400 1400);
FORCEADD Q_RES..2
(-1100 500);
FORCEPROP 1 LAST WATTAGE 1/16W
J 0
(-1060 475);
DISPLAY 0.510638 (-1060 475);
PAINT SKYBLUE (-1060 475);
FORCEPROP 1 LAST TOLERANCE 1%
J 0
(-1055 525);
DISPLAY 0.510638 (-1055 525);
PAINT SKYBLUE (-1055 525);
FORCEPROP 1 LAST VALUE 100
J 0
(-1055 575);
DISPLAY 0.510638 (-1055 575);
PAINT SKYBLUE (-1055 575);
FORCEPROP 1 LAST PACK_TYPE 0402LF
J 0
(-1060 325);
DISPLAY 0.510638 (-1060 325);
PAINT SKYBLUE (-1060 325);
FORCEPROP 1 LAST PART_NUMBER CS11002FB07
J 0
(-1060 375);
DISPLAY 0.510638 (-1060 375);
PAINT WHITE (-1060 375);
FORCEPROP 1 LAST MATERIAL CHIP
J 0
(-1060 425);
DISPLAY 0.510638 (-1060 425);
PAINT SKYBLUE (-1060 425);
FORCEPROP 1 LAST PATH I12
J 0
(-1050 675);
DISPLAY 0.978723 (-1050 675);
PAINT WHITE (-1050 675);
DISPLAY INVISIBLE (-1050 675);
FORCEPROP 2 LAST CDS_LIB pure_quanta
J 0
(-1100 500);
DISPLAY INVISIBLE (-1100 500);
FORCEPROP 1 LAST LOCATION R413
J 0
(-1055 625);
DISPLAY 0.702128 (-1055 625);
PAINT YELLOW (-1055 625);
FORCEPROP 1 LASTPIN (-1100 600) $PN 1
J 0
(-1095 562);
DISPLAY 0.808511 (-1095 562);
PAINT WHITE (-1095 562);
FORCEPROP 1 LASTPIN (-1100 400) $PN 2
J 0
(-1095 410);
DISPLAY 0.808511 (-1095 410);
PAINT WHITE (-1095 410);
FORCEPROP 0 LAST $SEC 1
J 0
(-1050 675);
DISPLAY 0.680851 (-1050 675);
PAINT MONO (-1050 675);
DISPLAY INVISIBLE (-1050 675);
FORCEPROP 0 LAST CDS_SEC 1
J 0
(-1050 675);
DISPLAY 1.021277 (-1050 675);
DISPLAY INVISIBLE (-1050 675);
FORCEADD UNIVERSAL_GND..1
(-175 550);
FORCEPROP 3 LASTPIN (-175 600) SIG_NAME GND\g
J 0
(-165 610);
DISPLAY 0.659574 (-165 610);
PAINT MONO (-165 610);
DISPLAY INVISIBLE (-165 610);
FORCEPROP 2 LAST CDS_LIB logical_power
J 0
(-175 550);
DISPLAY INVISIBLE (-175 550);
FORCEPROP 1 LAST HDL_POWER GND
J 1
(-150 475);
DISPLAY 0.702128 (-150 475);
PAINT GREEN (-150 475);
DISPLAY INVISIBLE (-150 475);
FORCEPROP 1 LAST PATH I13
J 0
(-100 550);
DISPLAY 0.872340 (-100 550);
PAINT AQUA (-100 550);
DISPLAY INVISIBLE (-100 550);
FORCEADD Q_RES..2
(-1100 1175);
FORCEPROP 1 LAST MATERIAL EMPTY
J 0
(-1060 1100);
DISPLAY 0.510638 (-1060 1100);
PAINT RED (-1060 1100);
FORCEPROP 1 LAST PART_NUMBER CS24702FB06
J 0
(-1060 1050);
DISPLAY 0.510638 (-1060 1050);
PAINT WHITE (-1060 1050);
FORCEPROP 1 LAST PACK_TYPE 0402LF
J 0
(-1060 1000);
DISPLAY 0.510638 (-1060 1000);
PAINT SKYBLUE (-1060 1000);
FORCEPROP 1 LAST TOLERANCE 1%
J 0
(-1055 1200);
DISPLAY 0.510638 (-1055 1200);
PAINT SKYBLUE (-1055 1200);
FORCEPROP 1 LAST WATTAGE 1/16W
J 0
(-1060 1150);
DISPLAY 0.510638 (-1060 1150);
PAINT SKYBLUE (-1060 1150);
FORCEPROP 1 LAST VALUE 4.7K
J 0
(-1055 1250);
DISPLAY 0.510638 (-1055 1250);
PAINT SKYBLUE (-1055 1250);
FORCEPROP 2 LAST CDS_LIB pure_quanta
J 0
(-1100 1175);
DISPLAY INVISIBLE (-1100 1175);
FORCEPROP 2 LAST SEC_TYPE 0402LF
J 0
(-1050 1400);
DISPLAY 0.680851 (-1050 1400);
DISPLAY INVISIBLE (-1050 1400);
FORCEPROP 1 LAST PATH I14
J 0
(-1050 1350);
DISPLAY 0.978723 (-1050 1350);
PAINT WHITE (-1050 1350);
DISPLAY INVISIBLE (-1050 1350);
FORCEPROP 1 LAST LOCATION R14
J 0
(-1055 1300);
DISPLAY 0.702128 (-1055 1300);
PAINT YELLOW (-1055 1300);
FORCEPROP 1 LASTPIN (-1100 1275) $PN 1
J 0
(-1095 1237);
DISPLAY 0.808511 (-1095 1237);
PAINT WHITE (-1095 1237);
FORCEPROP 1 LASTPIN (-1100 1075) $PN 2
J 0
(-1095 1085);
DISPLAY 0.808511 (-1095 1085);
PAINT WHITE (-1095 1085);
FORCEPROP 2 LAST SEC 1
J 0
(-1050 1400);
DISPLAY 0.680851 (-1050 1400);
PAINT MONO (-1050 1400);
DISPLAY INVISIBLE (-1050 1400);
FORCEADD M24128BWDW6TP..1
(225 775);
FORCEPROP 2 LAST PART_TYPE SMLF
J 0
(100 1125);
DISPLAY 0.510638 (100 1125);
PAINT SKYBLUE (100 1125);
FORCEPROP 2 LAST VALUE M24128-BWDW6TP
J 0
(100 1075);
DISPLAY 0.510638 (100 1075);
PAINT SKYBLUE (100 1075);
FORCEPROP 1 LAST PART_NUMBER AKE30Z0K610
J 0
(100 975);
DISPLAY 0.510638 (100 975);
PAINT WHITE (100 975);
FORCEPROP 1 LAST MATERIAL IC
J 0
(83 916);
DISPLAY 0.510638 (83 916);
PAINT SKYBLUE (83 916);
FORCEPROP 2 LAST CDS_LIB pure_quanta
J 0
(225 775);
DISPLAY INVISIBLE (225 775);
FORCEPROP 1 LAST CDS_LMAN_SYM_OUTLINE -150,125,150,-125
J 0
(225 775);
DISPLAY 0.468085 (225 775);
PAINT GREEN (225 775);
DISPLAY INVISIBLE (225 775);
FORCEPROP 1 LAST NEEDS_NO_SIZE TRUE
J 0
(225 775);
DISPLAY 0.723404 (225 775);
PAINT GREEN (225 775);
DISPLAY INVISIBLE (225 775);
FORCEPROP 1 LAST PATH I15
J 0
(225 775);
DISPLAY 0.723404 (225 775);
PAINT GREEN (225 775);
DISPLAY INVISIBLE (225 775);
FORCEPROP 1 LAST LOCATION U19
J 0
(100 1025);
DISPLAY 0.702128 (100 1025);
PAINT YELLOW (100 1025);
FORCEPROP 0 LASTPIN (-75 850) $PN 1
J 2
(-85 860);
DISPLAY 0.680851 (-85 860);
PAINT MONO (-85 860);
FORCEPROP 0 LASTPIN (-75 800) $PN 2
J 2
(-85 810);
DISPLAY 0.680851 (-85 810);
PAINT MONO (-85 810);
FORCEPROP 0 LASTPIN (-75 750) $PN 3
J 2
(-85 760);
DISPLAY 0.680851 (-85 760);
PAINT MONO (-85 760);
FORCEPROP 0 LASTPIN (525 750) $PN 6
J 0
(535 760);
DISPLAY 0.680851 (535 760);
PAINT MONO (535 760);
FORCEPROP 0 LASTPIN (525 700) $PN 5
J 0
(535 710);
DISPLAY 0.680851 (535 710);
PAINT MONO (535 710);
FORCEPROP 0 LASTPIN (525 850) $PN 8
J 0
(535 860);
DISPLAY 0.680851 (535 860);
PAINT MONO (535 860);
FORCEPROP 0 LASTPIN (-75 700) $PN 4
J 2
(-85 710);
DISPLAY 0.680851 (-85 710);
PAINT MONO (-85 710);
FORCEPROP 0 LASTPIN (525 800) $PN 7
J 0
(535 810);
DISPLAY 0.680851 (535 810);
PAINT MONO (535 810);
FORCEPROP 0 LAST $SEC 1
J 0
(25 1275);
DISPLAY 0.680851 (25 1275);
PAINT MONO (25 1275);
DISPLAY INVISIBLE (25 1275);
FORCEPROP 0 LAST CDS_SEC 1
J 0
(25 1275);
DISPLAY 0.680851 (25 1275);
DISPLAY INVISIBLE (25 1275);
FORCEADD UNIVERSAL_GND..1
(875 900);
FORCEPROP 3 LASTPIN (875 950) SIG_NAME GND\g
J 0
(885 960);
DISPLAY 0.659574 (885 960);
PAINT MONO (885 960);
DISPLAY INVISIBLE (885 960);
FORCEPROP 2 LAST CDS_LIB logical_power
J 0
(875 900);
DISPLAY INVISIBLE (875 900);
FORCEPROP 1 LAST HDL_POWER GND
J 1
(900 825);
DISPLAY 0.702128 (900 825);
PAINT GREEN (900 825);
DISPLAY INVISIBLE (900 825);
FORCEPROP 1 LAST PATH I16
J 0
(950 900);
DISPLAY 0.872340 (950 900);
PAINT AQUA (950 900);
DISPLAY INVISIBLE (950 900);
FORCEADD Q_CAP..1
(875 1150);
FORCEPROP 1 LAST VALUE 0.1UF
J 0
(925 1200);
DISPLAY 0.510638 (925 1200);
PAINT SKYBLUE (925 1200);
FORCEPROP 1 LAST VOLTAGE 25V
J 0
(925 1150);
DISPLAY 0.510638 (925 1150);
PAINT SKYBLUE (925 1150);
FORCEPROP 1 LAST TOLERANCE 10%
J 0
(925 1100);
DISPLAY 0.510638 (925 1100);
PAINT SKYBLUE (925 1100);
FORCEPROP 1 LAST MATERIAL X7R
J 0
(925 1050);
DISPLAY 0.510638 (925 1050);
PAINT SKYBLUE (925 1050);
FORCEPROP 1 LAST PACK_TYPE 0402
J 0
(925 1000);
DISPLAY 0.510638 (925 1000);
PAINT SKYBLUE (925 1000);
FORCEPROP 1 LAST PART_NUMBER CH4104K1B00
J 0
(925 950);
DISPLAY 0.510638 (925 950);
PAINT WHITE (925 950);
FORCEPROP 2 LAST CDS_LIB pure_quanta
J 0
(875 1150);
DISPLAY INVISIBLE (875 1150);
FORCEPROP 1 LAST PATH I17
J 0
(925 1300);
DISPLAY 0.978723 (925 1300);
PAINT WHITE (925 1300);
DISPLAY INVISIBLE (925 1300);
FORCEPROP 1 LAST LOCATION C192
J 0
(925 1250);
DISPLAY 0.702128 (925 1250);
PAINT YELLOW (925 1250);
FORCEPROP 1 LASTPIN (875 1250) $PN 1
J 0
(885 1230);
DISPLAY 0.808511 (885 1230);
PAINT WHITE (885 1230);
FORCEPROP 1 LASTPIN (875 1050) $PN 2
J 0
(885 1030);
DISPLAY 0.808511 (885 1030);
PAINT WHITE (885 1030);
FORCEPROP 0 LAST $SEC 1
J 0
(925 1300);
DISPLAY 0.680851 (925 1300);
PAINT MONO (925 1300);
DISPLAY INVISIBLE (925 1300);
FORCEPROP 0 LAST CDS_SEC 1
J 0
(925 1300);
DISPLAY 0.680851 (925 1300);
DISPLAY INVISIBLE (925 1300);
FORCEADD UNIVERSAL_POWER..1
(675 1500);
FORCEPROP 3 LASTPIN (675 1450) SIG_NAME P3V3_AUX\g
J 0
(685 1460);
DISPLAY 0.659574 (685 1460);
PAINT MONO (685 1460);
DISPLAY INVISIBLE (685 1460);
FORCEPROP 1 LAST HDL_POWER P3V3_AUX
J 1
(675 1550);
DISPLAY 0.702128 (675 1550);
PAINT GREEN (675 1550);
FORCEPROP 2 LAST CDS_LIB logical_power
J 0
(675 1500);
DISPLAY INVISIBLE (675 1500);
FORCEPROP 1 LAST PATH I18
J 0
(725 1525);
DISPLAY 0.872340 (725 1525);
PAINT AQUA (725 1525);
DISPLAY INVISIBLE (725 1525);
FORCEADD UNIVERSAL_GND..1
(1075 175);
FORCEPROP 3 LASTPIN (1075 225) SIG_NAME GND\g
J 0
(1085 235);
DISPLAY 0.659574 (1085 235);
PAINT MONO (1085 235);
DISPLAY INVISIBLE (1085 235);
FORCEPROP 1 LAST PATH I31
J 0
(1150 175);
DISPLAY 0.872340 (1150 175);
PAINT AQUA (1150 175);
DISPLAY INVISIBLE (1150 175);
FORCEPROP 1 LAST HDL_POWER GND
J 1
(1100 100);
DISPLAY 0.702128 (1100 100);
PAINT GREEN (1100 100);
DISPLAY INVISIBLE (1100 100);
FORCEPROP 2 LAST CDS_LIB logical_power
J 0
(1075 175);
DISPLAY INVISIBLE (1075 175);
FORCEADD Q_RES..2
(1075 450);
FORCEPROP 1 LAST WATTAGE 1/16W
J 0
(1115 425);
DISPLAY 0.510638 (1115 425);
PAINT SKYBLUE (1115 425);
FORCEPROP 1 LAST TOLERANCE 1%
J 0
(1120 475);
DISPLAY 0.510638 (1120 475);
PAINT SKYBLUE (1120 475);
FORCEPROP 1 LAST PART_NUMBER CS21002FB06
J 0
(1115 325);
DISPLAY 0.510638 (1115 325);
PAINT WHITE (1115 325);
FORCEPROP 1 LAST PACK_TYPE 0402LF
J 0
(1115 275);
DISPLAY 0.510638 (1115 275);
PAINT SKYBLUE (1115 275);
FORCEPROP 1 LAST VALUE 1K
J 0
(1120 525);
DISPLAY 0.510638 (1120 525);
PAINT SKYBLUE (1120 525);
FORCEPROP 1 LAST MATERIAL CHIP
J 0
(1115 375);
DISPLAY 0.510638 (1115 375);
PAINT SKYBLUE (1115 375);
FORCEPROP 1 LAST PATH I32
J 0
(1125 625);
DISPLAY 0.978723 (1125 625);
PAINT WHITE (1125 625);
DISPLAY INVISIBLE (1125 625);
FORCEPROP 2 LAST CDS_LIB pure_quanta
J 0
(1075 450);
DISPLAY INVISIBLE (1075 450);
FORCEPROP 1 LAST LOCATION R15
J 0
(1120 575);
DISPLAY 0.702128 (1120 575);
PAINT YELLOW (1120 575);
FORCEPROP 0 LAST $SEC 1
J 0
(1125 625);
DISPLAY 0.680851 (1125 625);
PAINT MONO (1125 625);
DISPLAY INVISIBLE (1125 625);
FORCEPROP 0 LAST CDS_SEC 1
J 0
(1125 625);
DISPLAY 1.021277 (1125 625);
DISPLAY INVISIBLE (1125 625);
FORCEPROP 1 LASTPIN (1075 550) $PN 1
J 0
(1080 512);
DISPLAY 0.808511 (1080 512);
PAINT WHITE (1080 512);
DISPLAY INVISIBLE (1080 512);
FORCEPROP 1 LASTPIN (1075 350) $PN 2
J 0
(1080 360);
DISPLAY 0.808511 (1080 360);
PAINT WHITE (1080 360);
DISPLAY INVISIBLE (1080 360);
FORCEADD Q_RES..1
(2275 700);
FORCEPROP 1 LAST MATERIAL CHIP
J 0
(2525 700);
DISPLAY 0.510638 (2525 700);
PAINT SKYBLUE (2525 700);
FORCEPROP 1 LAST VALUE 33.2
J 2
(2500 700);
DISPLAY 0.510638 (2500 700);
PAINT SKYBLUE (2500 700);
FORCEPROP 2 LAST CDS_LIB pure_quanta
J 0
(2275 700);
DISPLAY INVISIBLE (2275 700);
FORCEPROP 1 LAST PATH I33
J 0
(2225 850);
DISPLAY 0.978723 (2225 850);
PAINT WHITE (2225 850);
DISPLAY INVISIBLE (2225 850);
FORCEPROP 1 LAST WATTAGE 1/16W
J 2
(2525 750);
DISPLAY 0.510638 (2525 750);
PAINT SKYBLUE (2525 750);
DISPLAY INVISIBLE (2525 750);
FORCEPROP 1 LAST PACK_TYPE 0402LF
J 0
(2175 750);
DISPLAY 0.510638 (2175 750);
PAINT SKYBLUE (2175 750);
DISPLAY INVISIBLE (2175 750);
FORCEPROP 1 LAST PART_NUMBER CS03322FB03
J 0
(2025 800);
DISPLAY 0.510638 (2025 800);
PAINT WHITE (2025 800);
DISPLAY INVISIBLE (2025 800);
FORCEPROP 1 LAST TOLERANCE 1%
J 0
(2550 750);
DISPLAY 0.510638 (2550 750);
PAINT SKYBLUE (2550 750);
DISPLAY INVISIBLE (2550 750);
FORCEPROP 1 LAST LOCATION R421
J 0
(2025 700);
DISPLAY 0.702128 (2025 700);
PAINT YELLOW (2025 700);
FORCEPROP 1 LASTPIN (2175 700) $PN 1
J 0
(2187 712);
DISPLAY 0.808511 (2187 712);
PAINT WHITE (2187 712);
FORCEPROP 1 LASTPIN (2375 700) $PN 2
J 0
(2337 712);
DISPLAY 0.808511 (2337 712);
PAINT WHITE (2337 712);
FORCEPROP 0 LAST $SEC 1
J 0
(2725 750);
DISPLAY 0.680851 (2725 750);
PAINT MONO (2725 750);
DISPLAY INVISIBLE (2725 750);
FORCEPROP 0 LAST CDS_SEC 1
J 0
(2725 750);
DISPLAY 1.021277 (2725 750);
DISPLAY INVISIBLE (2725 750);
FORCEADD OFFPAGE..3
(3550 700);
FORCEPROP 2 LAST $XR1 27 
J 0
(3854 700);
DISPLAY 0.638298 (3854 700);
PAINT MONO (3854 700);
FORCEPROP 2 LAST $XR0 12 
J 0
(3764 700);
DISPLAY 0.638298 (3764 700);
PAINT MONO (3764 700);
FORCEPROP 1 LAST OFFPAGE TRUE
J 0
(3875 575);
DISPLAY 0.872340 (3875 575);
PAINT GREEN (3875 575);
DISPLAY INVISIBLE (3875 575);
FORCEPROP 1 LAST COMMENT_BODY TRUE
J 0
(3500 600);
DISPLAY 0.872340 (3500 600);
PAINT PEACH (3500 600);
DISPLAY INVISIBLE (3500 600);
FORCEPROP 2 LAST PATH I35
J 0
(3975 750);
DISPLAY 1.021277 (3975 750);
DISPLAY INVISIBLE (3975 750);
FORCEPROP 2 LAST CDS_LIB standard
J 0
(3550 700);
DISPLAY INVISIBLE (3550 700);
FORCEADD OFFPAGE..4
(3550 750);
FORCEPROP 2 LAST $XR1 27 
J 0
(3826 750);
DISPLAY 0.638298 (3826 750);
PAINT MONO (3826 750);
FORCEPROP 2 LAST $XR0 12 
J 0
(3736 750);
DISPLAY 0.638298 (3736 750);
PAINT MONO (3736 750);
FORCEPROP 1 LAST OFFPAGE TRUE
J 0
(3875 625);
DISPLAY 1.574468 (3875 625);
PAINT GREEN (3875 625);
DISPLAY INVISIBLE (3875 625);
FORCEPROP 1 LAST COMMENT_BODY TRUE
J 0
(3525 650);
DISPLAY 1.574468 (3525 650);
PAINT PEACH (3525 650);
DISPLAY INVISIBLE (3525 650);
FORCEPROP 2 LAST PATH I36
J 0
(3950 800);
DISPLAY 1.021277 (3950 800);
DISPLAY INVISIBLE (3950 800);
FORCEPROP 2 LAST CDS_LIB standard
J 0
(3550 750);
DISPLAY INVISIBLE (3550 750);
FORCEADD Q_RES..2
(-1725 2650);
FORCEPROP 1 LAST WATTAGE 1/16W
J 0
(-1685 2625);
DISPLAY 0.510638 (-1685 2625);
PAINT SKYBLUE (-1685 2625);
FORCEPROP 1 LAST PACK_TYPE 0402LF
J 0
(-1700 2525);
DISPLAY 0.510638 (-1700 2525);
PAINT SKYBLUE (-1700 2525);
FORCEPROP 1 LAST MATERIAL CHIP
J 0
(-1685 2575);
DISPLAY 0.510638 (-1685 2575);
PAINT SKYBLUE (-1685 2575);
FORCEPROP 1 LAST TOLERANCE 1%
J 0
(-1680 2675);
DISPLAY 0.510638 (-1680 2675);
PAINT SKYBLUE (-1680 2675);
FORCEPROP 1 LAST VALUE 1K
J 0
(-1680 2725);
DISPLAY 0.510638 (-1680 2725);
PAINT SKYBLUE (-1680 2725);
FORCEPROP 2 LAST SEC_TYPE 0402LF
J 0
(-1675 2875);
DISPLAY 0.680851 (-1675 2875);
DISPLAY INVISIBLE (-1675 2875);
FORCEPROP 2 LAST CDS_LIB pure_quanta
J 0
(-1725 2650);
DISPLAY INVISIBLE (-1725 2650);
FORCEPROP 1 LAST PART_NUMBER CS21002FB06
J 0
(-1685 2525);
DISPLAY 0.510638 (-1685 2525);
PAINT WHITE (-1685 2525);
DISPLAY INVISIBLE (-1685 2525);
FORCEPROP 1 LAST PATH I37
J 0
(-1675 2825);
DISPLAY 0.978723 (-1675 2825);
PAINT WHITE (-1675 2825);
DISPLAY INVISIBLE (-1675 2825);
FORCEPROP 1 LAST LOCATION R419
J 0
(-1680 2775);
DISPLAY 0.702128 (-1680 2775);
PAINT YELLOW (-1680 2775);
FORCEPROP 1 LASTPIN (-1725 2750) $PN 1
J 0
(-1720 2712);
DISPLAY 0.808511 (-1720 2712);
PAINT WHITE (-1720 2712);
FORCEPROP 1 LASTPIN (-1725 2550) $PN 2
J 0
(-1720 2560);
DISPLAY 0.808511 (-1720 2560);
PAINT WHITE (-1720 2560);
FORCEPROP 2 LAST SEC 1
J 0
(-1675 2875);
DISPLAY 0.680851 (-1675 2875);
PAINT MONO (-1675 2875);
DISPLAY INVISIBLE (-1675 2875);
FORCEADD UNIVERSAL_GND..1
(-1275 2325);
FORCEPROP 3 LASTPIN (-1275 2375) SIG_NAME GND\g
J 0
(-1265 2385);
DISPLAY 0.659574 (-1265 2385);
PAINT MONO (-1265 2385);
DISPLAY INVISIBLE (-1265 2385);
FORCEPROP 2 LAST CDS_LIB logical_power
J 0
(-1275 2325);
DISPLAY INVISIBLE (-1275 2325);
FORCEPROP 1 LAST HDL_POWER GND
J 1
(-1250 2250);
DISPLAY 0.702128 (-1250 2250);
PAINT GREEN (-1250 2250);
DISPLAY INVISIBLE (-1250 2250);
FORCEPROP 1 LAST PATH I38
J 0
(-1200 2325);
DISPLAY 0.872340 (-1200 2325);
PAINT AQUA (-1200 2325);
DISPLAY INVISIBLE (-1200 2325);
FORCEADD Q_RES..2
(-1175 2650);
FORCEPROP 1 LAST MATERIAL EMPTY
J 0
(-1135 2575);
DISPLAY 0.510638 (-1135 2575);
PAINT RED (-1135 2575);
FORCEPROP 1 LAST PACK_TYPE 0402LF
J 0
(-1135 2475);
DISPLAY 0.510638 (-1135 2475);
PAINT SKYBLUE (-1135 2475);
FORCEPROP 1 LAST WATTAGE 1/16W
J 0
(-1135 2625);
DISPLAY 0.510638 (-1135 2625);
PAINT SKYBLUE (-1135 2625);
FORCEPROP 1 LAST TOLERANCE 1%
J 0
(-1130 2675);
DISPLAY 0.510638 (-1130 2675);
PAINT SKYBLUE (-1130 2675);
FORCEPROP 1 LAST VALUE 1K
J 0
(-1130 2725);
DISPLAY 0.510638 (-1130 2725);
PAINT SKYBLUE (-1130 2725);
FORCEPROP 1 LAST PART_NUMBER CS21002FB06
J 0
(-1135 2525);
DISPLAY 0.510638 (-1135 2525);
PAINT WHITE (-1135 2525);
FORCEPROP 2 LAST CDS_LIB pure_quanta
J 0
(-1175 2650);
DISPLAY INVISIBLE (-1175 2650);
FORCEPROP 2 LAST SEC_TYPE 0402LF
J 0
(-1125 2875);
DISPLAY 0.680851 (-1125 2875);
DISPLAY INVISIBLE (-1125 2875);
FORCEPROP 1 LAST PATH I39
J 0
(-1125 2825);
DISPLAY 0.978723 (-1125 2825);
PAINT WHITE (-1125 2825);
DISPLAY INVISIBLE (-1125 2825);
FORCEPROP 1 LAST LOCATION R417
J 0
(-1130 2775);
DISPLAY 0.702128 (-1130 2775);
PAINT YELLOW (-1130 2775);
FORCEPROP 1 LASTPIN (-1175 2750) $PN 1
J 0
(-1170 2712);
DISPLAY 0.808511 (-1170 2712);
PAINT WHITE (-1170 2712);
FORCEPROP 1 LASTPIN (-1175 2550) $PN 2
J 0
(-1170 2560);
DISPLAY 0.808511 (-1170 2560);
PAINT WHITE (-1170 2560);
FORCEPROP 2 LAST SEC 1
J 0
(-1125 2875);
DISPLAY 0.680851 (-1125 2875);
PAINT MONO (-1125 2875);
DISPLAY INVISIBLE (-1125 2875);
FORCEADD Q_RES..2
(-1725 3350);
FORCEPROP 1 LAST MATERIAL EMPTY
J 0
(-1700 3250);
DISPLAY 0.510638 (-1700 3250);
PAINT RED (-1700 3250);
FORCEPROP 1 LAST PACK_TYPE 0402LF
J 0
(-1700 3200);
DISPLAY 0.510638 (-1700 3200);
PAINT SKYBLUE (-1700 3200);
FORCEPROP 1 LAST TOLERANCE 1%
J 0
(-1700 3350);
DISPLAY 0.510638 (-1700 3350);
PAINT SKYBLUE (-1700 3350);
FORCEPROP 1 LAST VALUE 4.7K
J 0
(-1700 3400);
DISPLAY 0.510638 (-1700 3400);
PAINT SKYBLUE (-1700 3400);
FORCEPROP 1 LAST WATTAGE 1/16W
J 0
(-1700 3300);
DISPLAY 0.510638 (-1700 3300);
PAINT SKYBLUE (-1700 3300);
FORCEPROP 1 LAST PATH I40
J 0
(-1675 3525);
DISPLAY 0.978723 (-1675 3525);
PAINT WHITE (-1675 3525);
DISPLAY INVISIBLE (-1675 3525);
FORCEPROP 1 LAST PART_NUMBER CS24702FB06
J 0
(-1685 3225);
DISPLAY 0.510638 (-1685 3225);
PAINT WHITE (-1685 3225);
DISPLAY INVISIBLE (-1685 3225);
FORCEPROP 2 LAST CDS_LIB pure_quanta
J 0
(-1725 3350);
DISPLAY INVISIBLE (-1725 3350);
FORCEPROP 1 LAST LOCATION R418
J 0
(-1680 3475);
DISPLAY 0.702128 (-1680 3475);
PAINT YELLOW (-1680 3475);
FORCEPROP 1 LASTPIN (-1725 3450) $PN 1
J 0
(-1720 3412);
DISPLAY 0.808511 (-1720 3412);
PAINT WHITE (-1720 3412);
FORCEPROP 1 LASTPIN (-1725 3250) $PN 2
J 0
(-1720 3260);
DISPLAY 0.808511 (-1720 3260);
PAINT WHITE (-1720 3260);
FORCEPROP 0 LAST $SEC 1
J 0
(-1675 3525);
DISPLAY 0.680851 (-1675 3525);
PAINT MONO (-1675 3525);
DISPLAY INVISIBLE (-1675 3525);
FORCEPROP 0 LAST CDS_SEC 1
J 0
(-1675 3525);
DISPLAY 0.680851 (-1675 3525);
DISPLAY INVISIBLE (-1675 3525);
FORCEADD Q_RES..2
(-1175 3350);
FORCEPROP 1 LAST TOLERANCE 1%
J 0
(-1130 3375);
DISPLAY 0.510638 (-1130 3375);
PAINT SKYBLUE (-1130 3375);
FORCEPROP 1 LAST MATERIAL CHIP
J 0
(-1135 3275);
DISPLAY 0.510638 (-1135 3275);
PAINT SKYBLUE (-1135 3275);
FORCEPROP 1 LAST PACK_TYPE 0402LF
J 0
(-1135 3175);
DISPLAY 0.510638 (-1135 3175);
PAINT SKYBLUE (-1135 3175);
FORCEPROP 1 LAST WATTAGE 1/16W
J 0
(-1135 3325);
DISPLAY 0.510638 (-1135 3325);
PAINT SKYBLUE (-1135 3325);
FORCEPROP 1 LAST VALUE 4.7K
J 0
(-1130 3425);
DISPLAY 0.510638 (-1130 3425);
PAINT SKYBLUE (-1130 3425);
FORCEPROP 1 LAST PART_NUMBER CS24702FB06
J 0
(-1150 3225);
DISPLAY 0.510638 (-1150 3225);
PAINT WHITE (-1150 3225);
FORCEPROP 2 LAST CDS_LIB pure_quanta
J 0
(-1175 3350);
DISPLAY INVISIBLE (-1175 3350);
FORCEPROP 1 LAST PATH I41
J 0
(-1125 3525);
DISPLAY 0.978723 (-1125 3525);
PAINT WHITE (-1125 3525);
DISPLAY INVISIBLE (-1125 3525);
FORCEPROP 1 LAST LOCATION R416
J 0
(-1130 3475);
DISPLAY 0.702128 (-1130 3475);
PAINT YELLOW (-1130 3475);
FORCEPROP 1 LASTPIN (-1175 3450) $PN 1
J 0
(-1170 3412);
DISPLAY 0.808511 (-1170 3412);
PAINT WHITE (-1170 3412);
FORCEPROP 1 LASTPIN (-1175 3250) $PN 2
J 0
(-1170 3260);
DISPLAY 0.808511 (-1170 3260);
PAINT WHITE (-1170 3260);
FORCEPROP 0 LAST $SEC 1
J 0
(-1125 3525);
DISPLAY 0.680851 (-1125 3525);
PAINT MONO (-1125 3525);
DISPLAY INVISIBLE (-1125 3525);
FORCEPROP 0 LAST CDS_SEC 1
J 0
(-1125 3525);
DISPLAY 0.680851 (-1125 3525);
DISPLAY INVISIBLE (-1125 3525);
FORCEADD UNIVERSAL_GND..1
(525 2700);
FORCEPROP 3 LASTPIN (525 2750) SIG_NAME GND\g
J 0
(535 2760);
DISPLAY 0.659574 (535 2760);
PAINT MONO (535 2760);
DISPLAY INVISIBLE (535 2760);
FORCEPROP 1 LAST PATH I52
J 0
(600 2700);
DISPLAY 0.872340 (600 2700);
PAINT AQUA (600 2700);
DISPLAY INVISIBLE (600 2700);
FORCEPROP 1 LAST HDL_POWER GND
J 1
(550 2625);
DISPLAY 0.702128 (550 2625);
PAINT GREEN (550 2625);
DISPLAY INVISIBLE (550 2625);
FORCEPROP 2 LAST CDS_LIB logical_power
J 0
(525 2700);
DISPLAY INVISIBLE (525 2700);
FORCEADD UNIVERSAL_POWER..1
(-325 4050);
FORCEPROP 3 LASTPIN (-325 4000) SIG_NAME P3V3_AUX\g
J 0
(-315 4010);
DISPLAY 0.659574 (-315 4010);
PAINT MONO (-315 4010);
DISPLAY INVISIBLE (-315 4010);
FORCEPROP 1 LAST HDL_POWER P3V3_AUX
J 1
(-325 4100);
DISPLAY 0.702128 (-325 4100);
PAINT GREEN (-325 4100);
FORCEPROP 1 LAST PATH I53
J 0
(-275 4075);
DISPLAY 0.872340 (-275 4075);
PAINT AQUA (-275 4075);
DISPLAY INVISIBLE (-275 4075);
FORCEPROP 2 LAST CDS_LIB logical_power
J 0
(-325 4050);
DISPLAY INVISIBLE (-325 4050);
FORCEADD Q_CAP..1
(-125 3775);
FORCEPROP 1 LAST VOLTAGE 25V
J 0
(-75 3775);
DISPLAY 0.510638 (-75 3775);
PAINT SKYBLUE (-75 3775);
FORCEPROP 1 LAST VALUE 0.1UF
J 0
(-75 3825);
DISPLAY 0.510638 (-75 3825);
PAINT SKYBLUE (-75 3825);
FORCEPROP 1 LAST TOLERANCE 10%
J 0
(-75 3725);
DISPLAY 0.510638 (-75 3725);
PAINT SKYBLUE (-75 3725);
FORCEPROP 1 LAST MATERIAL X7R
J 0
(-75 3675);
DISPLAY 0.510638 (-75 3675);
PAINT SKYBLUE (-75 3675);
FORCEPROP 1 LAST PACK_TYPE 0402
J 0
(-75 3625);
DISPLAY 0.510638 (-75 3625);
PAINT SKYBLUE (-75 3625);
FORCEPROP 1 LAST PART_NUMBER CH4104K1B00
J 0
(-75 3575);
DISPLAY 0.510638 (-75 3575);
PAINT WHITE (-75 3575);
FORCEPROP 1 LAST PATH I54
J 0
(-75 3925);
DISPLAY 0.978723 (-75 3925);
PAINT WHITE (-75 3925);
DISPLAY INVISIBLE (-75 3925);
FORCEPROP 2 LAST CDS_LIB pure_quanta
J 0
(-125 3775);
DISPLAY INVISIBLE (-125 3775);
FORCEPROP 1 LAST LOCATION C191
J 0
(-75 3875);
DISPLAY 0.702128 (-75 3875);
PAINT YELLOW (-75 3875);
FORCEPROP 1 LASTPIN (-125 3875) $PN 1
J 0
(-115 3855);
DISPLAY 0.808511 (-115 3855);
PAINT WHITE (-115 3855);
FORCEPROP 1 LASTPIN (-125 3675) $PN 2
J 0
(-115 3655);
DISPLAY 0.808511 (-115 3655);
PAINT WHITE (-115 3655);
FORCEPROP 0 LAST $SEC 1
J 0
(-75 3925);
DISPLAY 0.680851 (-75 3925);
PAINT MONO (-75 3925);
DISPLAY INVISIBLE (-75 3925);
FORCEPROP 0 LAST CDS_SEC 1
J 0
(-75 3925);
DISPLAY 0.680851 (-75 3925);
DISPLAY INVISIBLE (-75 3925);
FORCEADD UNIVERSAL_GND..1
(-125 3550);
FORCEPROP 3 LASTPIN (-125 3600) SIG_NAME GND\g
J 0
(-115 3610);
DISPLAY 0.659574 (-115 3610);
PAINT MONO (-115 3610);
DISPLAY INVISIBLE (-115 3610);
FORCEPROP 1 LAST PATH I55
J 0
(-50 3550);
DISPLAY 0.872340 (-50 3550);
PAINT AQUA (-50 3550);
DISPLAY INVISIBLE (-50 3550);
FORCEPROP 2 LAST CDS_LIB logical_power
J 0
(-125 3550);
DISPLAY INVISIBLE (-125 3550);
FORCEPROP 1 LAST HDL_POWER GND
J 1
(-100 3475);
DISPLAY 0.702128 (-100 3475);
PAINT GREEN (-100 3475);
DISPLAY INVISIBLE (-100 3475);
FORCEADD Q_RES..1
(1625 3025);
FORCEPROP 1 LAST MATERIAL CHIP
J 0
(1725 3025);
DISPLAY 0.510638 (1725 3025);
PAINT SKYBLUE (1725 3025);
FORCEPROP 1 LAST VALUE 49.9
J 2
(1550 3025);
DISPLAY 0.510638 (1550 3025);
PAINT SKYBLUE (1550 3025);
FORCEPROP 2 LAST CDS_LIB pure_quanta
J 0
(1625 3025);
DISPLAY INVISIBLE (1625 3025);
FORCEPROP 1 LAST WATTAGE 1/16W
J 2
(1600 2875);
DISPLAY 0.510638 (1600 2875);
PAINT SKYBLUE (1600 2875);
DISPLAY INVISIBLE (1600 2875);
FORCEPROP 1 LAST PACK_TYPE 0402LF
J 0
(1700 2925);
DISPLAY 0.510638 (1700 2925);
PAINT SKYBLUE (1700 2925);
DISPLAY INVISIBLE (1700 2925);
FORCEPROP 1 LAST PART_NUMBER CS04992FB07
J 0
(1100 2925);
DISPLAY 0.510638 (1100 2925);
PAINT WHITE (1100 2925);
DISPLAY INVISIBLE (1100 2925);
FORCEPROP 1 LAST TOLERANCE 1%
J 0
(1625 2925);
DISPLAY 0.510638 (1625 2925);
PAINT SKYBLUE (1625 2925);
DISPLAY INVISIBLE (1625 2925);
FORCEPROP 1 LAST PATH I56
J 0
(1575 3175);
DISPLAY 0.978723 (1575 3175);
PAINT WHITE (1575 3175);
DISPLAY INVISIBLE (1575 3175);
FORCEPROP 1 LAST LOCATION R410
J 0
(1825 3025);
DISPLAY 0.702128 (1825 3025);
PAINT YELLOW (1825 3025);
FORCEPROP 1 LASTPIN (1525 3025) $PN 1
J 0
(1537 3037);
DISPLAY 0.808511 (1537 3037);
PAINT WHITE (1537 3037);
FORCEPROP 1 LASTPIN (1725 3025) $PN 2
J 0
(1687 3037);
DISPLAY 0.808511 (1687 3037);
PAINT WHITE (1687 3037);
FORCEPROP 0 LAST $SEC 1
J 0
(1575 3125);
DISPLAY 0.680851 (1575 3125);
PAINT MONO (1575 3125);
DISPLAY INVISIBLE (1575 3125);
FORCEPROP 0 LAST CDS_SEC 1
J 0
(1750 3075);
DISPLAY 0.680851 (1750 3075);
DISPLAY INVISIBLE (1750 3075);
FORCEADD Q_RES..1
(1625 3125);
FORCEPROP 1 LAST MATERIAL CHIP
J 0
(1725 3125);
DISPLAY 0.510638 (1725 3125);
PAINT SKYBLUE (1725 3125);
FORCEPROP 1 LAST VALUE 49.9
J 2
(1550 3125);
DISPLAY 0.510638 (1550 3125);
PAINT SKYBLUE (1550 3125);
FORCEPROP 1 LAST PART_NUMBER CS04992FB07
J 0
(1475 3200);
DISPLAY 0.510638 (1475 3200);
PAINT WHITE (1475 3200);
FORCEPROP 1 LAST PACK_TYPE 0402LF
J 0
(1425 2975);
DISPLAY 0.510638 (1425 2975);
PAINT SKYBLUE (1425 2975);
DISPLAY INVISIBLE (1425 2975);
FORCEPROP 1 LAST WATTAGE 1/16W
J 2
(1350 2975);
DISPLAY 0.510638 (1350 2975);
PAINT SKYBLUE (1350 2975);
DISPLAY INVISIBLE (1350 2975);
FORCEPROP 1 LAST PATH I57
J 0
(1575 3275);
DISPLAY 0.978723 (1575 3275);
PAINT WHITE (1575 3275);
DISPLAY INVISIBLE (1575 3275);
FORCEPROP 2 LAST CDS_LIB pure_quanta
J 0
(1625 3125);
DISPLAY INVISIBLE (1625 3125);
FORCEPROP 1 LAST TOLERANCE 1%
J 0
(1775 3075);
DISPLAY 0.510638 (1775 3075);
PAINT SKYBLUE (1775 3075);
DISPLAY INVISIBLE (1775 3075);
FORCEPROP 1 LAST LOCATION R409
J 0
(1825 3125);
DISPLAY 0.702128 (1825 3125);
PAINT YELLOW (1825 3125);
FORCEPROP 1 LASTPIN (1525 3125) $PN 1
J 0
(1537 3137);
DISPLAY 0.808511 (1537 3137);
PAINT WHITE (1537 3137);
FORCEPROP 1 LASTPIN (1725 3125) $PN 2
J 0
(1687 3137);
DISPLAY 0.808511 (1687 3137);
PAINT WHITE (1687 3137);
FORCEPROP 0 LAST $SEC 1
J 0
(1575 3225);
DISPLAY 0.680851 (1575 3225);
PAINT MONO (1575 3225);
DISPLAY INVISIBLE (1575 3225);
FORCEPROP 0 LAST CDS_SEC 1
J 0
(1750 3175);
DISPLAY 0.680851 (1750 3175);
DISPLAY INVISIBLE (1750 3175);
FORCEADD UNIVERSAL_POWER..1
(-1175 3725);
FORCEPROP 3 LASTPIN (-1175 3675) SIG_NAME P3V3_AUX\g
J 0
(-1165 3685);
DISPLAY 0.659574 (-1165 3685);
PAINT MONO (-1165 3685);
DISPLAY INVISIBLE (-1165 3685);
FORCEPROP 1 LAST HDL_POWER P3V3_AUX
J 1
(-1175 3775);
DISPLAY 0.702128 (-1175 3775);
PAINT GREEN (-1175 3775);
FORCEPROP 2 LAST CDS_LIB logical_power
J 0
(-1175 3725);
DISPLAY INVISIBLE (-1175 3725);
FORCEPROP 1 LAST PATH I58
J 0
(-1125 3750);
DISPLAY 0.872340 (-1125 3750);
PAINT AQUA (-1125 3750);
DISPLAY INVISIBLE (-1125 3750);
FORCEADD OFFPAGE..3
(3200 3125);
FORCEPROP 2 LAST $XR2 10 
J 0
(3594 3125);
DISPLAY 0.638298 (3594 3125);
PAINT MONO (3594 3125);
FORCEPROP 2 LAST $XR1 27 
J 0
(3504 3125);
DISPLAY 0.638298 (3504 3125);
PAINT MONO (3504 3125);
FORCEPROP 2 LAST $XR0 12 
J 0
(3414 3125);
DISPLAY 0.638298 (3414 3125);
PAINT MONO (3414 3125);
FORCEPROP 1 LAST OFFPAGE TRUE
J 0
(3525 3000);
DISPLAY 0.872340 (3525 3000);
PAINT GREEN (3525 3000);
DISPLAY INVISIBLE (3525 3000);
FORCEPROP 1 LAST COMMENT_BODY TRUE
J 0
(3150 3025);
DISPLAY 0.872340 (3150 3025);
PAINT PEACH (3150 3025);
DISPLAY INVISIBLE (3150 3025);
FORCEPROP 2 LAST PATH I59
J 0
(3400 3200);
DISPLAY 0.680851 (3400 3200);
DISPLAY INVISIBLE (3400 3200);
FORCEPROP 2 LAST CDS_LIB standard
J 0
(3200 3125);
DISPLAY INVISIBLE (3200 3125);
FORCEADD Q_RES..2
(-1800 500);
FORCEPROP 1 LAST TOLERANCE 1%
J 0
(-1755 525);
DISPLAY 0.510638 (-1755 525);
PAINT SKYBLUE (-1755 525);
FORCEPROP 1 LAST VALUE 100
J 0
(-1755 575);
DISPLAY 0.510638 (-1755 575);
PAINT SKYBLUE (-1755 575);
FORCEPROP 1 LAST PACK_TYPE 0402LF
J 0
(-1775 375);
DISPLAY 0.510638 (-1775 375);
PAINT SKYBLUE (-1775 375);
FORCEPROP 1 LAST WATTAGE 1/16W
J 0
(-1760 475);
DISPLAY 0.510638 (-1760 475);
PAINT SKYBLUE (-1760 475);
FORCEPROP 1 LAST MATERIAL CHIP
J 0
(-1760 425);
DISPLAY 0.510638 (-1760 425);
PAINT SKYBLUE (-1760 425);
FORCEPROP 2 LAST CDS_LIB pure_quanta
J 0
(-1800 500);
DISPLAY INVISIBLE (-1800 500);
FORCEPROP 1 LAST PATH I6
J 0
(-1750 675);
DISPLAY 0.978723 (-1750 675);
PAINT WHITE (-1750 675);
DISPLAY INVISIBLE (-1750 675);
FORCEPROP 1 LAST PART_NUMBER CS11002FB07
J 0
(-1760 375);
DISPLAY 0.510638 (-1760 375);
PAINT WHITE (-1760 375);
DISPLAY INVISIBLE (-1760 375);
FORCEPROP 1 LAST LOCATION R411
J 0
(-1755 625);
DISPLAY 0.702128 (-1755 625);
PAINT YELLOW (-1755 625);
FORCEPROP 1 LASTPIN (-1800 600) $PN 1
J 0
(-1795 562);
DISPLAY 0.808511 (-1795 562);
PAINT WHITE (-1795 562);
FORCEPROP 1 LASTPIN (-1800 400) $PN 2
J 0
(-1795 410);
DISPLAY 0.808511 (-1795 410);
PAINT WHITE (-1795 410);
FORCEPROP 0 LAST $SEC 1
J 0
(-1750 675);
DISPLAY 0.680851 (-1750 675);
PAINT MONO (-1750 675);
DISPLAY INVISIBLE (-1750 675);
FORCEPROP 0 LAST CDS_SEC 1
J 0
(-1750 675);
DISPLAY 1.021277 (-1750 675);
DISPLAY INVISIBLE (-1750 675);
FORCEADD OFFPAGE..4
(3200 3025);
FORCEPROP 2 LAST $XR2 27 
J 0
(3566 3025);
DISPLAY 0.638298 (3566 3025);
PAINT MONO (3566 3025);
FORCEPROP 2 LAST $XR1 12 
J 0
(3476 3025);
DISPLAY 0.638298 (3476 3025);
PAINT MONO (3476 3025);
FORCEPROP 2 LAST $XR0 10 
J 0
(3386 3025);
DISPLAY 0.638298 (3386 3025);
PAINT MONO (3386 3025);
FORCEPROP 1 LAST OFFPAGE TRUE
J 0
(3525 2900);
DISPLAY 1.574468 (3525 2900);
PAINT GREEN (3525 2900);
DISPLAY INVISIBLE (3525 2900);
FORCEPROP 1 LAST COMMENT_BODY TRUE
J 0
(3175 2925);
DISPLAY 1.574468 (3175 2925);
PAINT PEACH (3175 2925);
DISPLAY INVISIBLE (3175 2925);
FORCEPROP 2 LAST PATH I60
J 0
(3375 3100);
DISPLAY 0.680851 (3375 3100);
DISPLAY INVISIBLE (3375 3100);
FORCEPROP 2 LAST CDS_LIB standard
J 0
(3200 3025);
DISPLAY INVISIBLE (3200 3025);
FORCEADD Q_RES..1
(1625 2925);
FORCEPROP 1 LAST PART_NUMBER CS31002FB08
J 0
(1425 2875);
DISPLAY 0.638298 (1425 2875);
FORCEPROP 1 LAST VALUE 10K
J 2
(1550 2925);
DISPLAY 0.638298 (1550 2925);
PAINT SKYBLUE (1550 2925);
FORCEPROP 1 LAST MATERIAL CHIP
J 0
(1725 2925);
DISPLAY 0.510638 (1725 2925);
PAINT SKYBLUE (1725 2925);
FORCEPROP 1 LAST TOLERANCE 1%
J 0
(1575 2850);
DISPLAY 0.787234 (1575 2850);
DISPLAY INVISIBLE (1575 2850);
FORCEPROP 1 LAST PACK_TYPE 0402LF
J 0
(1825 2800);
DISPLAY 0.787234 (1825 2800);
DISPLAY INVISIBLE (1825 2800);
FORCEPROP 2 LAST CDS_LIB pure_quanta
J 0
(1625 2925);
DISPLAY INVISIBLE (1625 2925);
FORCEPROP 1 LAST PATH I65
J 0
(1575 3075);
DISPLAY 0.978723 (1575 3075);
PAINT WHITE (1575 3075);
DISPLAY INVISIBLE (1575 3075);
FORCEPROP 1 LAST WATTAGE 1/16W
J 2
(1600 2775);
DISPLAY 0.787234 (1600 2775);
DISPLAY INVISIBLE (1600 2775);
FORCEPROP 1 LAST $LOCATION R54
J 0
(1825 2925);
DISPLAY 0.787234 (1825 2925);
PAINT YELLOW (1825 2925);
FORCEPROP 1 LASTPIN (1525 2925) $PN 1
J 0
(1537 2937);
DISPLAY 0.787234 (1537 2937);
PAINT MONO (1537 2937);
FORCEPROP 1 LASTPIN (1725 2925) $PN 2
J 0
(1687 2937);
DISPLAY 0.787234 (1687 2937);
PAINT MONO (1687 2937);
FORCEPROP 0 LAST CDS_LOCATION R54
J 0
(1575 3075);
DISPLAY 0.680851 (1575 3075);
DISPLAY INVISIBLE (1575 3075);
FORCEPROP 0 LAST $SEC 1
J 0
(1575 3075);
DISPLAY 0.680851 (1575 3075);
PAINT MONO (1575 3075);
DISPLAY INVISIBLE (1575 3075);
FORCEPROP 0 LAST CDS_SEC 1
J 0
(1575 3075);
DISPLAY 0.680851 (1575 3075);
DISPLAY INVISIBLE (1575 3075);
FORCEADD Q_RES..2
(-1450 2650);
FORCEPROP 1 LAST WATTAGE 1/16W
J 0
(-1410 2625);
DISPLAY 0.510638 (-1410 2625);
PAINT SKYBLUE (-1410 2625);
FORCEPROP 1 LAST MATERIAL EMPTY
J 0
(-1410 2575);
DISPLAY 0.510638 (-1410 2575);
PAINT RED (-1410 2575);
FORCEPROP 1 LAST TOLERANCE 1%
J 0
(-1405 2675);
DISPLAY 0.510638 (-1405 2675);
PAINT SKYBLUE (-1405 2675);
FORCEPROP 1 LAST VALUE 1K
J 0
(-1405 2725);
DISPLAY 0.510638 (-1405 2725);
PAINT SKYBLUE (-1405 2725);
FORCEPROP 1 LAST PART_NUMBER CS21002FB06
J 0
(-1410 2525);
DISPLAY 0.510638 (-1410 2525);
PAINT WHITE (-1410 2525);
FORCEPROP 1 LAST PACK_TYPE 0402LF
J 0
(-1410 2475);
DISPLAY 0.510638 (-1410 2475);
PAINT SKYBLUE (-1410 2475);
FORCEPROP 2 LAST CDS_LIB pure_quanta
J 0
(-1450 2650);
DISPLAY INVISIBLE (-1450 2650);
FORCEPROP 1 LAST PATH I66
J 0
(-1400 2825);
DISPLAY 0.978723 (-1400 2825);
PAINT WHITE (-1400 2825);
DISPLAY INVISIBLE (-1400 2825);
FORCEPROP 1 LAST $LOCATION R53
J 0
(-1405 2775);
DISPLAY 0.702128 (-1405 2775);
PAINT YELLOW (-1405 2775);
FORCEPROP 1 LASTPIN (-1450 2750) $PN 1
J 0
(-1445 2712);
DISPLAY 0.787234 (-1445 2712);
PAINT MONO (-1445 2712);
FORCEPROP 1 LASTPIN (-1450 2550) $PN 2
J 0
(-1445 2560);
DISPLAY 0.787234 (-1445 2560);
PAINT MONO (-1445 2560);
FORCEPROP 0 LAST CDS_LOCATION R53
J 0
(-1400 2825);
DISPLAY 0.680851 (-1400 2825);
DISPLAY INVISIBLE (-1400 2825);
FORCEPROP 0 LAST $SEC 1
J 0
(-1400 2825);
DISPLAY 0.680851 (-1400 2825);
PAINT MONO (-1400 2825);
DISPLAY INVISIBLE (-1400 2825);
FORCEPROP 0 LAST CDS_SEC 1
J 0
(-1400 2825);
DISPLAY 0.680851 (-1400 2825);
DISPLAY INVISIBLE (-1400 2825);
FORCEADD Q_RES..2
(-1450 3350);
FORCEPROP 1 LAST WATTAGE 1/16W
J 0
(-1410 3325);
DISPLAY 0.510638 (-1410 3325);
PAINT SKYBLUE (-1410 3325);
FORCEPROP 1 LAST VALUE 4.7K
J 0
(-1405 3425);
DISPLAY 0.510638 (-1405 3425);
PAINT SKYBLUE (-1405 3425);
FORCEPROP 1 LAST TOLERANCE 1%
J 0
(-1405 3375);
DISPLAY 0.510638 (-1405 3375);
PAINT SKYBLUE (-1405 3375);
FORCEPROP 1 LAST PACK_TYPE 0402LF
J 0
(-1410 3175);
DISPLAY 0.510638 (-1410 3175);
PAINT SKYBLUE (-1410 3175);
FORCEPROP 1 LAST PART_NUMBER CS24702FB06
J 0
(-1425 3225);
DISPLAY 0.510638 (-1425 3225);
PAINT WHITE (-1425 3225);
FORCEPROP 1 LAST MATERIAL CHIP
J 0
(-1410 3275);
DISPLAY 0.510638 (-1410 3275);
PAINT SKYBLUE (-1410 3275);
FORCEPROP 1 LAST PATH I67
J 0
(-1400 3525);
DISPLAY 0.978723 (-1400 3525);
PAINT WHITE (-1400 3525);
DISPLAY INVISIBLE (-1400 3525);
FORCEPROP 2 LAST CDS_LIB pure_quanta
J 0
(-1450 3350);
DISPLAY INVISIBLE (-1450 3350);
FORCEPROP 1 LAST $LOCATION R52
J 0
(-1405 3475);
DISPLAY 0.702128 (-1405 3475);
PAINT YELLOW (-1405 3475);
FORCEPROP 1 LASTPIN (-1450 3450) $PN 1
J 0
(-1445 3412);
DISPLAY 0.787234 (-1445 3412);
PAINT MONO (-1445 3412);
FORCEPROP 1 LASTPIN (-1450 3250) $PN 2
J 0
(-1445 3260);
DISPLAY 0.787234 (-1445 3260);
PAINT MONO (-1445 3260);
FORCEPROP 0 LAST CDS_LOCATION R52
J 0
(-1400 3525);
DISPLAY 0.680851 (-1400 3525);
DISPLAY INVISIBLE (-1400 3525);
FORCEPROP 0 LAST $SEC 1
J 0
(-1400 3525);
DISPLAY 0.680851 (-1400 3525);
PAINT MONO (-1400 3525);
DISPLAY INVISIBLE (-1400 3525);
FORCEPROP 0 LAST CDS_SEC 1
J 0
(-1400 3525);
DISPLAY 0.680851 (-1400 3525);
DISPLAY INVISIBLE (-1400 3525);
FORCEADD OFFPAGE..2
(2800 2925);
FORCEPROP 2 LAST $XR2 35 
J 0
(3169 2925);
DISPLAY 0.638298 (3169 2925);
PAINT MONO (3169 2925);
FORCEPROP 2 LAST $XR1 27 
J 0
(3079 2925);
DISPLAY 0.638298 (3079 2925);
PAINT MONO (3079 2925);
FORCEPROP 2 LAST $XR0 15 
J 0
(2989 2925);
DISPLAY 0.638298 (2989 2925);
PAINT MONO (2989 2925);
FORCEPROP 2 LAST CDS_LIB standard
J 0
(2800 2925);
DISPLAY INVISIBLE (2800 2925);
FORCEPROP 2 LAST PATH I68
J 0
(2975 3000);
DISPLAY 0.680851 (2975 3000);
DISPLAY INVISIBLE (2975 3000);
FORCEPROP 1 LAST OFFPAGE TRUE
J 0
(3125 2800);
DISPLAY 0.872340 (3125 2800);
DISPLAY INVISIBLE (3125 2800);
FORCEPROP 1 LAST COMMENT_BODY TRUE
J 0
(2755 2830);
DISPLAY 0.872340 (2755 2830);
PAINT GREEN (2755 2830);
DISPLAY INVISIBLE (2755 2830);
FORCEADD Q_RES..1
(2275 750);
FORCEPROP 1 LAST MATERIAL CHIP
J 0
(2525 750);
DISPLAY 0.510638 (2525 750);
PAINT SKYBLUE (2525 750);
FORCEPROP 1 LAST VALUE 150
J 2
(2475 750);
DISPLAY 0.510638 (2475 750);
PAINT SKYBLUE (2475 750);
FORCEPROP 1 LAST PART_NUMBER CS11502FB07
J 0
(2150 800);
DISPLAY 0.510638 (2150 800);
PAINT WHITE (2150 800);
FORCEPROP 2 LAST CDS_LIB pure_quanta
J 0
(2275 750);
DISPLAY INVISIBLE (2275 750);
FORCEPROP 1 LAST PATH I69
J 0
(2225 900);
DISPLAY 0.978723 (2225 900);
PAINT WHITE (2225 900);
DISPLAY INVISIBLE (2225 900);
FORCEPROP 1 LAST WATTAGE 1/16W
J 2
(2375 850);
DISPLAY 0.510638 (2375 850);
PAINT SKYBLUE (2375 850);
DISPLAY INVISIBLE (2375 850);
FORCEPROP 1 LAST TOLERANCE 1%
J 0
(2750 850);
DISPLAY 0.510638 (2750 850);
PAINT SKYBLUE (2750 850);
DISPLAY INVISIBLE (2750 850);
FORCEPROP 1 LAST PACK_TYPE 0402LF
J 0
(2575 850);
DISPLAY 0.510638 (2575 850);
PAINT SKYBLUE (2575 850);
DISPLAY INVISIBLE (2575 850);
FORCEPROP 1 LAST LOCATION R420
J 0
(2025 750);
DISPLAY 0.702128 (2025 750);
PAINT YELLOW (2025 750);
FORCEPROP 1 LASTPIN (2175 750) $PN 1
J 0
(2187 762);
DISPLAY 0.787234 (2187 762);
PAINT MONO (2187 762);
FORCEPROP 1 LASTPIN (2375 750) $PN 2
J 0
(2337 762);
DISPLAY 0.787234 (2337 762);
PAINT MONO (2337 762);
FORCEPROP 0 LAST $SEC 1
J 0
(2150 825);
DISPLAY 0.680851 (2150 825);
PAINT MONO (2150 825);
DISPLAY INVISIBLE (2150 825);
FORCEPROP 0 LAST CDS_SEC 1
J 0
(2150 825);
DISPLAY 0.680851 (2150 825);
DISPLAY INVISIBLE (2150 825);
FORCEADD UNIVERSAL_GND..1
(-1650 25);
FORCEPROP 3 LASTPIN (-1650 75) SIG_NAME GND\g
J 0
(-1640 85);
DISPLAY 0.659574 (-1640 85);
PAINT MONO (-1640 85);
DISPLAY INVISIBLE (-1640 85);
FORCEPROP 2 LAST CDS_LIB logical_power
J 0
(-1650 25);
DISPLAY INVISIBLE (-1650 25);
FORCEPROP 1 LAST HDL_POWER GND
J 1
(-1625 -50);
DISPLAY 0.702128 (-1625 -50);
PAINT GREEN (-1625 -50);
DISPLAY INVISIBLE (-1625 -50);
FORCEPROP 1 LAST PATH I7
J 0
(-1575 25);
DISPLAY 0.872340 (-1575 25);
PAINT AQUA (-1575 25);
DISPLAY INVISIBLE (-1575 25);
FORCEADD CONN8_TSW10407FD..1
(175 2975);
FORCEPROP 1 LAST MATERIAL EMPTY
J 0
(56 3182);
DISPLAY 0.723404 (56 3182);
PAINT RED (56 3182);
FORCEPROP 2 LAST PART_TYPE THLF
J 0
(69 3444);
DISPLAY 0.680851 (69 3444);
FORCEPROP 1 LAST PART_NUMBER DFHD08MS225
J 0
(50 3225);
DISPLAY 0.723404 (50 3225);
PAINT GREEN (50 3225);
FORCEPROP 2 LAST VALUE CONN8_TSW-104-07-F-D
J 0
(69 3394);
DISPLAY 0.680851 (69 3394);
FORCEPROP 1 LAST CDS_LMAN_SYM_OUTLINE -125,200,125,-200
J 0
(175 2975);
DISPLAY 0.468085 (175 2975);
PAINT GREEN (175 2975);
DISPLAY INVISIBLE (175 2975);
FORCEPROP 1 LAST NEEDS_NO_SIZE TRUE
J 0
(175 2975);
DISPLAY 0.723404 (175 2975);
PAINT GREEN (175 2975);
DISPLAY INVISIBLE (175 2975);
FORCEPROP 1 LAST PATH I71
J 0
(175 2975);
DISPLAY 0.723404 (175 2975);
PAINT GREEN (175 2975);
DISPLAY INVISIBLE (175 2975);
FORCEPROP 2 LAST CDS_LIB pure_quanta
J 0
(175 2975);
DISPLAY INVISIBLE (175 2975);
FORCEPROP 1 LAST LOCATION J14
J 0
(50 3350);
DISPLAY 0.723404 (50 3350);
PAINT GREEN (50 3350);
FORCEPROP 0 LASTPIN (-100 3125) $PN 1
J 2
(-110 3135);
DISPLAY 0.680851 (-110 3135);
PAINT MONO (-110 3135);
FORCEPROP 0 LASTPIN (450 3125) $PN 2
J 0
(460 3135);
DISPLAY 0.680851 (460 3135);
PAINT MONO (460 3135);
FORCEPROP 0 LASTPIN (-100 3025) $PN 3
J 2
(-110 3035);
DISPLAY 0.680851 (-110 3035);
PAINT MONO (-110 3035);
FORCEPROP 0 LASTPIN (450 3025) $PN 4
J 0
(460 3035);
DISPLAY 0.680851 (460 3035);
PAINT MONO (460 3035);
FORCEPROP 0 LASTPIN (-100 2925) $PN 5
J 2
(-110 2935);
DISPLAY 0.680851 (-110 2935);
PAINT MONO (-110 2935);
FORCEPROP 0 LASTPIN (450 2925) $PN 6
J 0
(460 2935);
DISPLAY 0.680851 (460 2935);
PAINT MONO (460 2935);
FORCEPROP 0 LASTPIN (-100 2825) $PN 7
J 2
(-110 2835);
DISPLAY 0.680851 (-110 2835);
PAINT MONO (-110 2835);
FORCEPROP 0 LASTPIN (450 2825) $PN 8
J 0
(460 2835);
DISPLAY 0.680851 (460 2835);
PAINT MONO (460 2835);
FORCEPROP 0 LAST $SEC 1
J 0
(75 3500);
DISPLAY 0.680851 (75 3500);
PAINT MONO (75 3500);
DISPLAY INVISIBLE (75 3500);
FORCEPROP 0 LAST CDS_SEC 1
J 0
(75 3500);
DISPLAY 0.680851 (75 3500);
DISPLAY INVISIBLE (75 3500);
FORCEADD Q_RES..2
(-1450 500);
FORCEPROP 1 LAST VALUE 100
J 0
(-1405 575);
DISPLAY 0.510638 (-1405 575);
PAINT SKYBLUE (-1405 575);
FORCEPROP 1 LAST MATERIAL CHIP
J 0
(-1410 425);
DISPLAY 0.510638 (-1410 425);
PAINT SKYBLUE (-1410 425);
FORCEPROP 1 LAST PACK_TYPE 0402LF
J 0
(-1400 375);
DISPLAY 0.510638 (-1400 375);
PAINT SKYBLUE (-1400 375);
FORCEPROP 1 LAST TOLERANCE 1%
J 0
(-1405 525);
DISPLAY 0.510638 (-1405 525);
PAINT SKYBLUE (-1405 525);
FORCEPROP 1 LAST WATTAGE 1/16W
J 0
(-1410 475);
DISPLAY 0.510638 (-1410 475);
PAINT SKYBLUE (-1410 475);
FORCEPROP 2 LAST CDS_LIB pure_quanta
J 0
(-1450 500);
DISPLAY INVISIBLE (-1450 500);
FORCEPROP 1 LAST PATH I8
J 0
(-1400 675);
DISPLAY 0.978723 (-1400 675);
PAINT WHITE (-1400 675);
DISPLAY INVISIBLE (-1400 675);
FORCEPROP 1 LAST PART_NUMBER CS11002FB07
J 0
(-1410 375);
DISPLAY 0.510638 (-1410 375);
PAINT WHITE (-1410 375);
DISPLAY INVISIBLE (-1410 375);
FORCEPROP 1 LAST LOCATION R412
J 0
(-1405 625);
DISPLAY 0.702128 (-1405 625);
PAINT YELLOW (-1405 625);
FORCEPROP 1 LASTPIN (-1450 600) $PN 1
J 0
(-1445 562);
DISPLAY 0.808511 (-1445 562);
PAINT WHITE (-1445 562);
FORCEPROP 1 LASTPIN (-1450 400) $PN 2
J 0
(-1445 410);
DISPLAY 0.808511 (-1445 410);
PAINT WHITE (-1445 410);
FORCEPROP 0 LAST $SEC 1
J 0
(-1400 675);
DISPLAY 0.680851 (-1400 675);
PAINT MONO (-1400 675);
DISPLAY INVISIBLE (-1400 675);
FORCEPROP 0 LAST CDS_SEC 1
J 0
(-1400 675);
DISPLAY 1.021277 (-1400 675);
DISPLAY INVISIBLE (-1400 675);
FORCEADD Q_RES..2
(-1800 1175);
FORCEPROP 1 LAST WATTAGE 1/16W
J 0
(-1750 1100);
DISPLAY 0.510638 (-1750 1100);
PAINT SKYBLUE (-1750 1100);
FORCEPROP 1 LAST PACK_TYPE 0402LF
J 0
(-1750 1150);
DISPLAY 0.510638 (-1750 1150);
PAINT SKYBLUE (-1750 1150);
FORCEPROP 1 LAST MATERIAL EMPTY
J 0
(-1750 1050);
DISPLAY 0.510638 (-1750 1050);
PAINT RED (-1750 1050);
FORCEPROP 1 LAST TOLERANCE 1%
J 0
(-1750 1200);
DISPLAY 0.510638 (-1750 1200);
PAINT SKYBLUE (-1750 1200);
FORCEPROP 1 LAST VALUE 4.7K
J 0
(-1750 1250);
DISPLAY 0.510638 (-1750 1250);
PAINT SKYBLUE (-1750 1250);
FORCEPROP 2 LAST CDS_LIB pure_quanta
J 0
(-1800 1175);
DISPLAY INVISIBLE (-1800 1175);
FORCEPROP 2 LAST SEC_TYPE 0402LF
J 0
(-1750 1400);
DISPLAY 0.680851 (-1750 1400);
DISPLAY INVISIBLE (-1750 1400);
FORCEPROP 1 LAST PATH I9
J 0
(-1750 1350);
DISPLAY 0.978723 (-1750 1350);
PAINT WHITE (-1750 1350);
DISPLAY INVISIBLE (-1750 1350);
FORCEPROP 1 LAST PART_NUMBER CS24702FB06
J 0
(-1755 1050);
DISPLAY 0.510638 (-1755 1050);
PAINT WHITE (-1755 1050);
DISPLAY INVISIBLE (-1755 1050);
FORCEPROP 1 LAST LOCATION R12
J 0
(-1755 1300);
DISPLAY 0.702128 (-1755 1300);
PAINT YELLOW (-1755 1300);
FORCEPROP 1 LASTPIN (-1800 1275) $PN 1
J 0
(-1795 1237);
DISPLAY 0.808511 (-1795 1237);
PAINT WHITE (-1795 1237);
FORCEPROP 1 LASTPIN (-1800 1075) $PN 2
J 0
(-1795 1085);
DISPLAY 0.808511 (-1795 1085);
PAINT WHITE (-1795 1085);
FORCEPROP 2 LAST SEC 1
J 0
(-1750 1400);
DISPLAY 0.680851 (-1750 1400);
PAINT MONO (-1750 1400);
DISPLAY INVISIBLE (-1750 1400);
FORCEADD QUANTA_TITLE_BLOCK_C..1
(5000 -2100);
FORCEPROP 0 LAST CDS_CON_LAST_MODIFIED Fri Aug 25 17:25:41 2023
J 0
(3115 -2085);
DISPLAY INVISIBLE (3115 -2085);
FORCEPROP 2 LAST Q_DEPT 
J 1
(1237 -2051);
DISPLAY 1.957447 (1237 -2051);
PAINT GREEN (1237 -2051);
FORCEPROP 1 LAST CUSTOM_TXT_CDS <CON_LAST_MODIFIED>
J 0
(3115 -2085);
DISPLAY 0.978723 (3115 -2085);
FORCEPROP 2 LAST CUSTOM_TXT_CDS <XR_PAGE_TITLE>
J 0
(-2890 3150);
DISPLAY 0.638298 (-2890 3150);
PAINT PINK (-2890 3150);
DISPLAY INVISIBLE (-2890 3150);
FORCEPROP 1 LAST CUSTOM_TXT_CDS <NAME_2>
J 0
(1825 -2050);
FORCEPROP 1 LAST CUSTOM_TXT_CDS <NAME_1>
J 0
(1825 -1925);
FORCEPROP 1 LAST CUSTOM_TXT_CDS <Q_NUMBER>
J 0
(3597 -1997);
DISPLAY 1.212766 (3597 -1997);
FORCEPROP 1 LAST CUSTOM_TXT_CDS <Q_PROJ>
J 0
(2618 -1998);
DISPLAY 1.212766 (2618 -1998);
FORCEPROP 1 LAST CUSTOM_TXT_CDS <Q_REV>
J 0
(4816 -1997);
DISPLAY 1.212766 (4816 -1997);
FORCEPROP 1 LAST CUSTOM_TXT_CDS <CON_PAGE_NUM> OF <CON_TOTAL_PAGES>
J 0
(4554 -2082);
DISPLAY 0.978723 (4554 -2082);
FORCEPROP 1 LAST Q_TITLE EEPROM & TEMP SENSOR
J 0
(-4366 -2074);
DISPLAY 2.446809 (-4366 -2074);
PAINT GREEN (-4366 -2074);
FORCEPROP 2 LAST PAGE_BORDER TRUE
J 0
(-2890 3150);
DISPLAY 0.638298 (-2890 3150);
PAINT PINK (-2890 3150);
DISPLAY INVISIBLE (-2890 3150);
FORCEPROP 2 LAST CDS_LIB pure_quanta
J 0
(5000 -2100);
DISPLAY INVISIBLE (5000 -2100);
FORCEPROP 1 LAST CDS_LMAN_SYM_OUTLINE -9475,6775,100,-125
J 0
(5000 -2100);
DISPLAY 0.468085 (5000 -2100);
PAINT GREEN (5000 -2100);
DISPLAY INVISIBLE (5000 -2100);
FORCEPROP 1 LAST COMMENT_BODY TRUE
J 0
(5012 -2113);
DISPLAY 0.978723 (5012 -2113);
PAINT PEACH (5012 -2113);
DISPLAY INVISIBLE (5012 -2113);
FORCEPROP 2 LAST CDS_XR_PAGE_TITLE CR-26 : @SCM_LIB.SCM(SCH_1):PAGE26
J 0
(-2890 3150);
DISPLAY 0.638298 (-2890 3150);
PAINT PINK (-2890 3150);
DISPLAY INVISIBLE (-2890 3150);
FORCEADD DNS..1
(200 2975);
PAINT RED (200 2975);
FORCEPROP 1 LAST COMMENT_BODY TRUE
R 1
J 0
(275 2750);
DISPLAY 0.872340 (275 2750);
PAINT PEACH (275 2750);
DISPLAY INVISIBLE (275 2750);
FORCEPROP 2 LAST CDS_LIB mstr_misc
J 0
(200 2975);
DISPLAY INVISIBLE (200 2975);
FORCEADD DNS..1
(-1800 1150);
PAINT RED (-1800 1150);
FORCEPROP 2 LAST CDS_LIB mstr_misc
J 0
(-1800 1150);
DISPLAY INVISIBLE (-1800 1150);
FORCEPROP 1 LAST COMMENT_BODY TRUE
R 1
J 0
(-1725 925);
DISPLAY 0.872340 (-1725 925);
PAINT PEACH (-1725 925);
DISPLAY INVISIBLE (-1725 925);
FORCEADD DNS..1
(-1425 1175);
PAINT RED (-1425 1175);
FORCEPROP 2 LAST CDS_LIB mstr_misc
J 0
(-1425 1175);
DISPLAY INVISIBLE (-1425 1175);
FORCEPROP 1 LAST COMMENT_BODY TRUE
R 1
J 0
(-1350 950);
DISPLAY 0.872340 (-1350 950);
PAINT PEACH (-1350 950);
DISPLAY INVISIBLE (-1350 950);
FORCEADD DNS..1
(-1075 1175);
PAINT RED (-1075 1175);
FORCEPROP 2 LAST CDS_LIB mstr_misc
J 0
(-1075 1175);
DISPLAY INVISIBLE (-1075 1175);
FORCEPROP 1 LAST COMMENT_BODY TRUE
R 1
J 0
(-1000 950);
DISPLAY 0.872340 (-1000 950);
PAINT PEACH (-1000 950);
DISPLAY INVISIBLE (-1000 950);
FORCEADD DNS..1
(-1725 3375);
PAINT RED (-1725 3375);
FORCEPROP 1 LAST COMMENT_BODY TRUE
R 1
J 0
(-1650 3150);
DISPLAY 0.872340 (-1650 3150);
PAINT PEACH (-1650 3150);
DISPLAY INVISIBLE (-1650 3150);
FORCEPROP 2 LAST CDS_LIB mstr_misc
J 0
(-1725 3375);
DISPLAY INVISIBLE (-1725 3375);
FORCEADD DNS..1
(-1150 2650);
PAINT RED (-1150 2650);
FORCEPROP 2 LAST CDS_LIB mstr_misc
J 0
(-1150 2650);
DISPLAY INVISIBLE (-1150 2650);
FORCEPROP 1 LAST COMMENT_BODY TRUE
R 1
J 0
(-1075 2425);
DISPLAY 0.872340 (-1075 2425);
PAINT PEACH (-1075 2425);
DISPLAY INVISIBLE (-1075 2425);
FORCEADD DNS..1
(-1475 2675);
PAINT RED (-1475 2675);
FORCEPROP 2 LAST CDS_LIB mstr_misc
J 0
(-1475 2675);
DISPLAY INVISIBLE (-1475 2675);
FORCEPROP 1 LAST COMMENT_BODY TRUE
R 1
J 0
(-1400 2450);
DISPLAY 0.872340 (-1400 2450);
PAINT PEACH (-1400 2450);
DISPLAY INVISIBLE (-1400 2450);
WIRE 16 -1 (-1175 3575)(-1175 3675);
WIRE 16 -1 (-1175 3575)(-1175 3450);
WIRE 16 -1 (-1450 3575)(-1175 3575);
WIRE 16 -1 (675 1350)(675 1450);
WIRE 16 -1 (675 1350)(875 1350);
WIRE 16 -1 (675 850)(675 1350);
WIRE 16 -1 (-1800 1500)(-1800 1600);
WIRE 16 -1 (-1800 1500)(-1450 1500);
WIRE 16 -1 (-1800 1275)(-1800 1500);
WIRE 16 -1 (-325 4000)(-325 3925);
WIRE 16 -1 (525 2825)(525 2750);
WIRE 16 -1 (450 2825)(525 2825);
WIRE 16 -1 (-175 700)(-175 600);
WIRE 16 -1 (-75 700)(-175 700);
WIRE 16 -1 (875 1050)(875 950);
WIRE 16 -1 (-1650 200)(-1650 75);
WIRE 16 -1 (-1800 200)(-1650 200);
WIRE 16 -1 (-1650 200)(-1450 200);
WIRE 16 -1 (1075 350)(1075 225);
WIRE 16 -1 (-125 3675)(-125 3600);
WIRE 16 -1 (-1275 2450)(-1275 2375);
WIRE 16 -1 (-1450 2450)(-1275 2450);
WIRE 16 -1 (-1275 2450)(-1175 2450);
WIRE 16 -1 (-1450 3575)(-1450 3450);
WIRE 16 -1 (-1725 3575)(-1725 3450);
WIRE 16 -1 (-1725 3575)(-1450 3575);
WIRE 16 -1 (-1725 2750)(-1725 2825);
WIRE 16 -1 (-1725 2825)(-100 2825);
FORCEPROP 2 LAST SIG_NAME TMC75_A2
J 0
(-885 2835);
DISPLAY 0.808511 (-885 2835);
WIRE 16 -1 (-1725 3250)(-1725 2825);
WIRE 16 -1 (-1175 2450)(-1175 2550);
WIRE 16 -1 (-1450 2450)(-1450 2550);
WIRE 16 -1 (-1725 2450)(-1450 2450);
WIRE 16 -1 (-1725 2550)(-1725 2450);
WIRE 16 -1 (450 2925)(1525 2925);
FORCEPROP 2 LAST SIG_NAME SMB_BMC_ALERT16_R_N
J 0
(540 2935);
DISPLAY 0.851064 (540 2935);
WIRE 16 -1 (450 3025)(1525 3025);
FORCEPROP 2 LAST SIG_NAME SMB_TMP421_BMC_MM2_SCL
J 0
(540 3035);
DISPLAY 0.808511 (540 3035);
WIRE 16 -1 (450 3125)(1525 3125);
FORCEPROP 2 LAST SIG_NAME SMB_TMP421_BMC_MM2_SDA
J 0
(540 3135);
DISPLAY 0.808511 (540 3135);
WIRE 16 3135 (-125 2575)(425 2575);
WIRE 16 3135 (-125 3325)(-125 2575);
WIRE 16 3135 (425 2575)(425 3325);
WIRE 16 3135 (425 3325)(-125 3325);
WIRE 16 -1 (-100 3125)(-300 3125);
WIRE 16 -1 (-125 3925)(-125 3875);
WIRE 16 -1 (-300 3925)(-125 3925);
WIRE 16 -1 (-300 3925)(-300 3125);
WIRE 16 -1 (-325 3925)(-300 3925);
WIRE 16 -1 (-1800 850)(-1800 1075);
WIRE 16 -1 (-1800 850)(-75 850);
FORCEPROP 2 LAST SIG_NAME FRU_E0
J 0
(-635 860);
DISPLAY 0.808511 (-635 860);
WIRE 16 -1 (-1800 600)(-1800 850);
WIRE 16 -1 (-1450 800)(-1450 1075);
WIRE 16 -1 (-1450 800)(-75 800);
FORCEPROP 2 LAST SIG_NAME FRU_E1
J 0
(-635 810);
DISPLAY 0.808511 (-635 810);
WIRE 16 -1 (-1450 600)(-1450 800);
WIRE 16 -1 (-1100 750)(-1100 1075);
WIRE 16 -1 (-75 750)(-1100 750);
FORCEPROP 2 LAST SIG_NAME FRU_E2
J 0
(-635 760);
DISPLAY 0.808511 (-635 760);
WIRE 16 -1 (-1100 600)(-1100 750);
WIRE 16 -1 (2175 700)(525 700);
FORCEPROP 2 LAST SIG_NAME SMB_BMC_MM16_R2_SDA
J 0
(1190 710);
DISPLAY 0.808511 (1190 710);
WIRE 16 -1 (1075 800)(1075 550);
WIRE 16 -1 (525 800)(1075 800);
FORCEPROP 2 LAST SIG_NAME PD_FRU_WC_N
J 0
(615 810);
DISPLAY 0.808511 (615 810);
WIRE 16 -1 (2375 700)(3500 700);
FORCEPROP 2 LAST SIG_NAME SMB_BMC_MM16_SDA
J 0
(2715 710);
DISPLAY 0.808511 (2715 710);
WIRE 16 -1 (2175 750)(525 750);
FORCEPROP 2 LAST SIG_NAME SMB_BMC_MM16_R2_SCL
J 0
(1190 760);
DISPLAY 0.808511 (1190 760);
WIRE 16 -1 (2375 750)(3500 750);
FORCEPROP 2 LAST SIG_NAME SMB_BMC_MM16_SCL
J 0
(2715 760);
DISPLAY 0.808511 (2715 760);
WIRE 16 3135 (2150 725)(2400 725);
WIRE 16 3135 (2150 875)(2150 725);
WIRE 16 3135 (2400 725)(2400 875);
WIRE 16 3135 (2400 875)(2150 875);
WIRE 16 -1 (-1450 3250)(-1450 2925);
WIRE 16 -1 (-1450 2925)(-100 2925);
FORCEPROP 2 LAST SIG_NAME TMC75_A1
J 0
(-885 2935);
DISPLAY 0.808511 (-885 2935);
WIRE 16 -1 (-1450 2750)(-1450 2925);
WIRE 16 -1 (1725 2925)(2750 2925);
FORCEPROP 2 LAST SIG_NAME SMB_BMC_ALERT16_N
J 0
(2065 2935);
DISPLAY 0.851064 (2065 2935);
WIRE 16 -1 (1725 3025)(3150 3025);
FORCEPROP 2 LAST SIG_NAME SMB_BMC_MM2_SCL
J 0
(2215 3035);
DISPLAY 0.808511 (2215 3035);
WIRE 16 -1 (1725 3125)(3150 3125);
FORCEPROP 2 LAST SIG_NAME SMB_BMC_MM2_SDA
J 0
(2215 3135);
DISPLAY 0.808511 (2215 3135);
WIRE 16 -1 (-1175 3250)(-1175 3025);
WIRE 16 -1 (-1175 3025)(-100 3025);
FORCEPROP 2 LAST SIG_NAME TMC75_A0
J 0
(-885 3035);
DISPLAY 0.808511 (-885 3035);
WIRE 16 -1 (-1175 2750)(-1175 3025);
WIRE 16 -1 (-1100 1275)(-1100 1500);
WIRE 16 -1 (-1450 1275)(-1450 1500);
WIRE 16 -1 (-1450 1500)(-1100 1500);
WIRE 16 -1 (525 850)(675 850);
WIRE 16 -1 (875 1350)(875 1250);
WIRE 16 -1 (-1100 200)(-1100 400);
WIRE 16 -1 (-1450 400)(-1450 200);
WIRE 16 -1 (-1450 200)(-1100 200);
WIRE 16 -1 (-1800 400)(-1800 200);
DOT 1 (-1725 2825);
DOT 1 (-1175 3575);
DOT 1 (-1275 2450);
DOT 1 (-1450 2925);
DOT 1 (-300 3925);
DOT 1 (675 1350);
DOT 1 (-1450 2450);
DOT 1 (-1175 3025);
DOT 1 (-1450 3575);
DOT 1 (-1650 200);
DOT 1 (-1800 850);
DOT 1 (-1450 200);
DOT 1 (-1450 800);
DOT 1 (-1800 1500);
DOT 1 (-1450 1500);
DOT 1 (-1100 750);
FORCENOTE
SMBUS ADDRESS 0X96
(-2200 2125) 0;
DISPLAY LEFT (-2200 2125);
DISPLAY 1.595745 (-2200 2125);
PAINT WHITE (-2200 2125);
FORCENOTE
DUMMY FOOTPRINT FOR REMOTE TEMP SENSOR ASSEMBLE
(-4100 4275) 0;
DISPLAY LEFT (-4100 4275);
DISPLAY 2.000000 (-4100 4275);
FORCENOTE
CHANGE TO HEADER_20220804
(325 3525) 0;
DISPLAY LEFT (325 3525);
DISPLAY 1.595745 (325 3525);
PAINT WHITE (325 3525);
FORCENOTE
EEPROM ADDRESS: 0XA0
(-575 0) 0;
DISPLAY LEFT (-575 0);
DISPLAY 1.595745 (-575 0);
PAINT WHITE (-575 0);
FORCENOTE
CHANGE TO 150OHM_20220804
(2200 900) 0;
DISPLAY LEFT (2200 900);
DISPLAY 0.808511 (2200 900);
PAINT WHITE (2200 900);
FORCENOTE
$CDS_IMAGE|clipboard_4.jpg|3000|1500
(3150 -650) 0;
DISPLAY LEFT (3150 -650);
QUIT
